(kicad_pcb
	(version 20260206)
	(generator "pcbnew")
	(generator_version "10.0")
	(general
		(thickness 1.6)
		(legacy_teardrops no)
	)
	(paper "A4")
	(title_block
		(title "04192023_DAF0TMB3IC0_F0TG_MB_C_brd_V02_OCP.brd")
		(comment 1 "Grand Teton / footprints 184-190 of 8354")
	)
	(layers
		(0 "F.Cu" signal "TOP")
		(4 "In1.Cu" signal "GND")
		(6 "In2.Cu" signal "IN1")
		(8 "In3.Cu" signal "GND1")
		(10 "In4.Cu" signal "IN2")
		(12 "In5.Cu" signal "GND2")
		(14 "In6.Cu" signal "IN3")
		(16 "In7.Cu" signal "GND3")
		(18 "In8.Cu" signal "VCC")
		(20 "In9.Cu" signal "VCC1")
		(22 "In10.Cu" signal "GND4")
		(24 "In11.Cu" signal "IN4")
		(26 "In12.Cu" signal "GND5")
		(28 "In13.Cu" signal "IN5")
		(30 "In14.Cu" signal "GND6")
		(32 "In15.Cu" signal "IN6")
		(34 "In16.Cu" signal "GND7")
		(2 "B.Cu" signal "BOTTOM")
		(9 "F.Adhes" user "F.Adhesive")
		(11 "B.Adhes" user "B.Adhesive")
		(13 "F.Paste" user "Package Geometry/Pastemask Top")
		(15 "B.Paste" user "Package Geometry/Pastemask Bottom")
		(5 "F.SilkS" user "Ref Des/Silkscreen Top")
		(7 "B.SilkS" user "Ref Des/Silkscreen Bottom")
		(1 "F.Mask" user "Board Geometry/Soldermask Top")
		(3 "B.Mask" user "Board Geometry/Soldermask Bottom")
		(17 "Dwgs.User" user "User.Drawings")
		(19 "Cmts.User" user "User.Comments")
		(21 "Eco1.User" user "User.Eco1")
		(23 "Eco2.User" user "User.Eco2")
		(25 "Edge.Cuts" user "Board Geometry/Outline")
		(27 "Margin" user)
		(31 "F.CrtYd" user "Package Geometry/Place Bound Top")
		(29 "B.CrtYd" user "Package Geometry/Place Bound Bottom")
		(35 "F.Fab" user "Ref Des/Assembly Top")
		(33 "B.Fab" user "Ref Des/Assembly Bottom")
	)
	(footprint ""
		(layer "F.Cu")
		(at 111.476028 -256.012442 90)
		(property "Reference" "C2460"
			(at 0 0 90)
			(layer "F.SilkS")
			(hide yes)
			(effects
				(font
					(size 1.27 1.27)
				)
			)
		)
		(property "Value" ""
			(at 0 0 90)
			(layer "F.Fab")
			(effects
				(font
					(size 1.27 1.27)
				)
			)
		)
		(duplicate_pad_numbers_are_jumpers no)
		(fp_line
			(start 0.7874 -0.4064)
			(end 0.7874 0.4064)
			(stroke
				(width 0.1524)
				(type default)
			)
			(layer "F.SilkS")
		)
		(fp_line
			(start -0.7874 -0.4064)
			(end 0.7874 -0.4064)
			(stroke
				(width 0.1524)
				(type default)
			)
			(layer "F.SilkS")
		)
		(fp_line
			(start 0.7874 0.4064)
			(end -0.7874 0.4064)
			(stroke
				(width 0.1524)
				(type default)
			)
			(layer "F.SilkS")
		)
		(fp_line
			(start -0.7874 0.4064)
			(end -0.7874 -0.4064)
			(stroke
				(width 0.1524)
				(type default)
			)
			(layer "F.SilkS")
		)
		(fp_line
			(start -0.12065 -0.305054)
			(end -0.12065 -0.2794)
			(stroke
				(width 0.1)
				(type default)
			)
			(layer "F.Fab")
		)
		(fp_line
			(start -0.67945 -0.305054)
			(end -0.12065 -0.305054)
			(stroke
				(width 0.1)
				(type default)
			)
			(layer "F.Fab")
		)
		(fp_line
			(start 0.67945 -0.3048)
			(end 0.67945 0.3048)
			(stroke
				(width 0.1)
				(type default)
			)
			(layer "F.Fab")
		)
		(fp_line
			(start 0.12065 -0.3048)
			(end 0.67945 -0.3048)
			(stroke
				(width 0.1)
				(type default)
			)
			(layer "F.Fab")
		)
		(fp_line
			(start 0.12065 -0.2794)
			(end 0.12065 -0.3048)
			(stroke
				(width 0.1)
				(type default)
			)
			(layer "F.Fab")
		)
		(fp_line
			(start -0.12065 -0.2794)
			(end 0.12065 -0.2794)
			(stroke
				(width 0.1)
				(type default)
			)
			(layer "F.Fab")
		)
		(fp_line
			(start 0.120396 0.2794)
			(end -0.12065 0.2794)
			(stroke
				(width 0.1)
				(type default)
			)
			(layer "F.Fab")
		)
		(fp_line
			(start -0.12065 0.2794)
			(end -0.12065 0.3048)
			(stroke
				(width 0.1)
				(type default)
			)
			(layer "F.Fab")
		)
		(fp_line
			(start 0.67945 0.3048)
			(end 0.120396 0.3048)
			(stroke
				(width 0.1)
				(type default)
			)
			(layer "F.Fab")
		)
		(fp_line
			(start 0.120396 0.3048)
			(end 0.120396 0.2794)
			(stroke
				(width 0.1)
				(type default)
			)
			(layer "F.Fab")
		)
		(fp_line
			(start -0.12065 0.3048)
			(end -0.67945 0.3048)
			(stroke
				(width 0.1)
				(type default)
			)
			(layer "F.Fab")
		)
		(fp_line
			(start -0.67945 0.3048)
			(end -0.67945 -0.305054)
			(stroke
				(width 0.1)
				(type default)
			)
			(layer "F.Fab")
		)
		(pad "1" smd circle
			(at -0.40005 0 90)
			(size 0 0)
			(layers "F.Cu" "F.Mask" "F.Paste")
			(net "PVDDCR_SOC_P1")
		)
		(pad "2" smd circle
			(at 0.40005 0 90)
			(size 0 0)
			(layers "F.Cu" "F.Mask" "F.Paste")
			(net "GND")
		)
	)
	(footprint ""
		(layer "F.Cu")
		(at 38.180772 -53.837332 -90)
		(property "Reference" "R8026"
			(at 0 0 270)
			(layer "F.SilkS")
			(hide yes)
			(effects
				(font
					(size 1.27 1.27)
				)
			)
		)
		(property "Value" ""
			(at 0 0 270)
			(layer "F.Fab")
			(effects
				(font
					(size 1.27 1.27)
				)
			)
		)
		(duplicate_pad_numbers_are_jumpers no)
		(fp_line
			(start -0.7874 0.4064)
			(end -0.7874 -0.4064)
			(stroke
				(width 0.1524)
				(type default)
			)
			(layer "F.SilkS")
		)
		(fp_line
			(start 0.7874 0.4064)
			(end -0.7874 0.4064)
			(stroke
				(width 0.1524)
				(type default)
			)
			(layer "F.SilkS")
		)
		(fp_line
			(start -0.7874 -0.4064)
			(end 0.7874 -0.4064)
			(stroke
				(width 0.1524)
				(type default)
			)
			(layer "F.SilkS")
		)
		(fp_line
			(start 0.7874 -0.4064)
			(end 0.7874 0.4064)
			(stroke
				(width 0.1524)
				(type default)
			)
			(layer "F.SilkS")
		)
		(fp_line
			(start -0.67945 0.3048)
			(end -0.67945 -0.305054)
			(stroke
				(width 0.1)
				(type default)
			)
			(layer "F.Fab")
		)
		(fp_line
			(start -0.12065 0.3048)
			(end -0.67945 0.3048)
			(stroke
				(width 0.1)
				(type default)
			)
			(layer "F.Fab")
		)
		(fp_line
			(start 0.120396 0.3048)
			(end 0.120396 0.2794)
			(stroke
				(width 0.1)
				(type default)
			)
			(layer "F.Fab")
		)
		(fp_line
			(start 0.67945 0.3048)
			(end 0.120396 0.3048)
			(stroke
				(width 0.1)
				(type default)
			)
			(layer "F.Fab")
		)
		(fp_line
			(start -0.12065 0.2794)
			(end -0.12065 0.3048)
			(stroke
				(width 0.1)
				(type default)
			)
			(layer "F.Fab")
		)
		(fp_line
			(start 0.120396 0.2794)
			(end -0.12065 0.2794)
			(stroke
				(width 0.1)
				(type default)
			)
			(layer "F.Fab")
		)
		(fp_line
			(start -0.12065 -0.2794)
			(end 0.12065 -0.2794)
			(stroke
				(width 0.1)
				(type default)
			)
			(layer "F.Fab")
		)
		(fp_line
			(start 0.12065 -0.2794)
			(end 0.12065 -0.3048)
			(stroke
				(width 0.1)
				(type default)
			)
			(layer "F.Fab")
		)
		(fp_line
			(start 0.12065 -0.3048)
			(end 0.67945 -0.3048)
			(stroke
				(width 0.1)
				(type default)
			)
			(layer "F.Fab")
		)
		(fp_line
			(start 0.67945 -0.3048)
			(end 0.67945 0.3048)
			(stroke
				(width 0.1)
				(type default)
			)
			(layer "F.Fab")
		)
		(fp_line
			(start -0.67945 -0.305054)
			(end -0.12065 -0.305054)
			(stroke
				(width 0.1)
				(type default)
			)
			(layer "F.Fab")
		)
		(fp_line
			(start -0.12065 -0.305054)
			(end -0.12065 -0.2794)
			(stroke
				(width 0.1)
				(type default)
			)
			(layer "F.Fab")
		)
		(pad "1" smd circle
			(at -0.40005 0 270)
			(size 0 0)
			(layers "F.Cu" "F.Mask" "F.Paste")
			(net "LED_P12V_PSU_R2")
		)
		(pad "2" smd circle
			(at 0.40005 0 270)
			(size 0 0)
			(layers "F.Cu" "F.Mask" "F.Paste")
			(net "LED_P12V_PSU_R3")
		)
	)
	(footprint ""
		(layer "F.Cu")
		(at 257.951478 -106.909108)
		(property "Reference" "R3191"
			(at 0 0 0)
			(layer "F.SilkS")
			(hide yes)
			(effects
				(font
					(size 1.27 1.27)
				)
			)
		)
		(property "Value" ""
			(at 0 0 0)
			(layer "F.Fab")
			(effects
				(font
					(size 1.27 1.27)
				)
			)
		)
		(duplicate_pad_numbers_are_jumpers no)
		(fp_line
			(start -0.7874 -0.4064)
			(end 0.7874 -0.4064)
			(stroke
				(width 0.1524)
				(type default)
			)
			(layer "F.SilkS")
		)
		(fp_line
			(start -0.7874 0.4064)
			(end -0.7874 -0.4064)
			(stroke
				(width 0.1524)
				(type default)
			)
			(layer "F.SilkS")
		)
		(fp_line
			(start 0.7874 -0.4064)
			(end 0.7874 0.4064)
			(stroke
				(width 0.1524)
				(type default)
			)
			(layer "F.SilkS")
		)
		(fp_line
			(start 0.7874 0.4064)
			(end -0.7874 0.4064)
			(stroke
				(width 0.1524)
				(type default)
			)
			(layer "F.SilkS")
		)
		(fp_line
			(start -0.67945 -0.305054)
			(end -0.12065 -0.305054)
			(stroke
				(width 0.1)
				(type default)
			)
			(layer "F.Fab")
		)
		(fp_line
			(start -0.67945 0.3048)
			(end -0.67945 -0.305054)
			(stroke
				(width 0.1)
				(type default)
			)
			(layer "F.Fab")
		)
		(fp_line
			(start -0.12065 -0.305054)
			(end -0.12065 -0.2794)
			(stroke
				(width 0.1)
				(type default)
			)
			(layer "F.Fab")
		)
		(fp_line
			(start -0.12065 -0.2794)
			(end 0.12065 -0.2794)
			(stroke
				(width 0.1)
				(type default)
			)
			(layer "F.Fab")
		)
		(fp_line
			(start -0.12065 0.2794)
			(end -0.12065 0.3048)
			(stroke
				(width 0.1)
				(type default)
			)
			(layer "F.Fab")
		)
		(fp_line
			(start -0.12065 0.3048)
			(end -0.67945 0.3048)
			(stroke
				(width 0.1)
				(type default)
			)
			(layer "F.Fab")
		)
		(fp_line
			(start 0.120396 0.2794)
			(end -0.12065 0.2794)
			(stroke
				(width 0.1)
				(type default)
			)
			(layer "F.Fab")
		)
		(fp_line
			(start 0.120396 0.3048)
			(end 0.120396 0.2794)
			(stroke
				(width 0.1)
				(type default)
			)
			(layer "F.Fab")
		)
		(fp_line
			(start 0.12065 -0.3048)
			(end 0.67945 -0.3048)
			(stroke
				(width 0.1)
				(type default)
			)
			(layer "F.Fab")
		)
		(fp_line
			(start 0.12065 -0.2794)
			(end 0.12065 -0.3048)
			(stroke
				(width 0.1)
				(type default)
			)
			(layer "F.Fab")
		)
		(fp_line
			(start 0.67945 -0.3048)
			(end 0.67945 0.3048)
			(stroke
				(width 0.1)
				(type default)
			)
			(layer "F.Fab")
		)
		(fp_line
			(start 0.67945 0.3048)
			(end 0.120396 0.3048)
			(stroke
				(width 0.1)
				(type default)
			)
			(layer "F.Fab")
		)
		(pad "1" smd circle
			(at -0.40005 0)
			(size 0 0)
			(layers "F.Cu" "F.Mask" "F.Paste")
			(net "OCP_V3_2_PWRBRK_BUFF_N")
		)
		(pad "2" smd circle
			(at 0.40005 0)
			(size 0 0)
			(layers "F.Cu" "F.Mask" "F.Paste")
			(net "OCP_V3_2_PWRBRK_N")
		)
	)
	(footprint ""
		(layer "F.Cu")
		(at 239.152684 -53.821838)
		(property "Reference" "C1993"
			(at 0 0 0)
			(layer "F.SilkS")
			(hide yes)
			(effects
				(font
					(size 1.27 1.27)
				)
			)
		)
		(property "Value" ""
			(at 0 0 0)
			(layer "F.Fab")
			(effects
				(font
					(size 1.27 1.27)
				)
			)
		)
		(duplicate_pad_numbers_are_jumpers no)
		(fp_line
			(start -0.299974 -0.150114)
			(end 0.299974 -0.150114)
			(stroke
				(width 0.1)
				(type default)
			)
			(layer "F.Fab")
		)
		(fp_line
			(start -0.299974 0.150114)
			(end -0.299974 -0.150114)
			(stroke
				(width 0.1)
				(type default)
			)
			(layer "F.Fab")
		)
		(fp_line
			(start 0.299974 -0.150114)
			(end 0.299974 0.150114)
			(stroke
				(width 0.1)
				(type default)
			)
			(layer "F.Fab")
		)
		(fp_line
			(start 0.299974 0.150114)
			(end -0.299974 0.150114)
			(stroke
				(width 0.1)
				(type default)
			)
			(layer "F.Fab")
		)
		(pad "1" smd rect
			(at -0.2667 0)
			(size 0.3048 0.381)
			(layers "F.Cu" "F.Mask" "F.Paste")
			(net "P3E_CPU0_P4_TX_C_DP<1>")
		)
		(pad "2" smd rect
			(at 0.2667 0)
			(size 0.3048 0.381)
			(layers "F.Cu" "F.Mask" "F.Paste")
			(net "P3E_CPU0_P4_TX_DP<1>")
		)
	)
	(footprint ""
		(layer "F.Cu")
		(at 134.23138 -394.3477 -90)
		(property "Reference" "R6901"
			(at 0 0 270)
			(layer "F.SilkS")
			(hide yes)
			(effects
				(font
					(size 1.27 1.27)
				)
			)
		)
		(property "Value" ""
			(at 0 0 270)
			(layer "F.Fab")
			(effects
				(font
					(size 1.27 1.27)
				)
			)
		)
		(duplicate_pad_numbers_are_jumpers no)
		(fp_line
			(start -0.32512 0.175006)
			(end -0.32512 -0.175006)
			(stroke
				(width 0.1)
				(type default)
			)
			(layer "F.Fab")
		)
		(fp_line
			(start 0.32512 0.175006)
			(end -0.32512 0.175006)
			(stroke
				(width 0.1)
				(type default)
			)
			(layer "F.Fab")
		)
		(fp_line
			(start -0.32512 -0.175006)
			(end 0.32512 -0.175006)
			(stroke
				(width 0.1)
				(type default)
			)
			(layer "F.Fab")
		)
		(fp_line
			(start 0.32512 -0.175006)
			(end 0.32512 0.175006)
			(stroke
				(width 0.1)
				(type default)
			)
			(layer "F.Fab")
		)
		(pad "1" smd rect
			(at -0.2667 0 270)
			(size 0.3048 0.381)
			(layers "F.Cu" "F.Mask" "F.Paste")
			(net "RT_CPU1_P3_VQPS")
		)
		(pad "2" smd rect
			(at 0.2667 0 90)
			(size 0.3048 0.381)
			(layers "F.Cu" "F.Mask" "F.Paste")
			(net "GND")
		)
	)
	(footprint ""
		(layer "F.Cu")
		(at 409.434792 -140.884656 180)
		(property "Reference" "PC1853"
			(at 0 0 180)
			(layer "F.SilkS")
			(hide yes)
			(effects
				(font
					(size 1.27 1.27)
				)
			)
		)
		(property "Value" ""
			(at 0 0 180)
			(layer "F.Fab")
			(effects
				(font
					(size 1.27 1.27)
				)
			)
		)
		(duplicate_pad_numbers_are_jumpers no)
		(fp_line
			(start 0.7874 0.4064)
			(end -0.7874 0.4064)
			(stroke
				(width 0.1524)
				(type default)
			)
			(layer "F.SilkS")
		)
		(fp_line
			(start 0.7874 -0.4064)
			(end 0.7874 0.4064)
			(stroke
				(width 0.1524)
				(type default)
			)
			(layer "F.SilkS")
		)
		(fp_line
			(start -0.7874 0.4064)
			(end -0.7874 -0.4064)
			(stroke
				(width 0.1524)
				(type default)
			)
			(layer "F.SilkS")
		)
		(fp_line
			(start -0.7874 -0.4064)
			(end 0.7874 -0.4064)
			(stroke
				(width 0.1524)
				(type default)
			)
			(layer "F.SilkS")
		)
		(fp_line
			(start 0.67945 0.3048)
			(end 0.120396 0.3048)
			(stroke
				(width 0.1)
				(type default)
			)
			(layer "F.Fab")
		)
		(fp_line
			(start 0.67945 -0.3048)
			(end 0.67945 0.3048)
			(stroke
				(width 0.1)
				(type default)
			)
			(layer "F.Fab")
		)
		(fp_line
			(start 0.12065 -0.2794)
			(end 0.12065 -0.3048)
			(stroke
				(width 0.1)
				(type default)
			)
			(layer "F.Fab")
		)
		(fp_line
			(start 0.12065 -0.3048)
			(end 0.67945 -0.3048)
			(stroke
				(width 0.1)
				(type default)
			)
			(layer "F.Fab")
		)
		(fp_line
			(start 0.120396 0.3048)
			(end 0.120396 0.2794)
			(stroke
				(width 0.1)
				(type default)
			)
			(layer "F.Fab")
		)
		(fp_line
			(start 0.120396 0.2794)
			(end -0.12065 0.2794)
			(stroke
				(width 0.1)
				(type default)
			)
			(layer "F.Fab")
		)
		(fp_line
			(start -0.12065 0.3048)
			(end -0.67945 0.3048)
			(stroke
				(width 0.1)
				(type default)
			)
			(layer "F.Fab")
		)
		(fp_line
			(start -0.12065 0.2794)
			(end -0.12065 0.3048)
			(stroke
				(width 0.1)
				(type default)
			)
			(layer "F.Fab")
		)
		(fp_line
			(start -0.12065 -0.2794)
			(end 0.12065 -0.2794)
			(stroke
				(width 0.1)
				(type default)
			)
			(layer "F.Fab")
		)
		(fp_line
			(start -0.12065 -0.305054)
			(end -0.12065 -0.2794)
			(stroke
				(width 0.1)
				(type default)
			)
			(layer "F.Fab")
		)
		(fp_line
			(start -0.67945 0.3048)
			(end -0.67945 -0.305054)
			(stroke
				(width 0.1)
				(type default)
			)
			(layer "F.Fab")
		)
		(fp_line
			(start -0.67945 -0.305054)
			(end -0.12065 -0.305054)
			(stroke
				(width 0.1)
				(type default)
			)
			(layer "F.Fab")
		)
		(pad "1" smd circle
			(at -0.40005 0 180)
			(size 0 0)
			(layers "F.Cu" "F.Mask" "F.Paste")
			(net "P5V_AUX_REF")
		)
		(pad "2" smd circle
			(at 0.40005 0 180)
			(size 0 0)
			(layers "F.Cu" "F.Mask" "F.Paste")
			(net "GND")
		)
	)
	(footprint ""
		(layer "F.Cu")
		(at 105.659936 -123.623832 -90)
		(property "Reference" "Q19"
			(at -0.177546 1.643126 90)
			(unlocked yes)
			(layer "F.SilkS")
			(effects
				(font
					(size 0.7874 0.5842)
					(thickness 0.1524)
				)
			)
		)
		(property "Value" ""
			(at 0 0 270)
			(layer "F.Fab")
			(effects
				(font
					(size 1.27 1.27)
				)
			)
		)
		(duplicate_pad_numbers_are_jumpers no)
		(fp_line
			(start -1.7018 1.100074)
			(end -1.7018 -1.100074)
			(stroke
				(width 0.1524)
				(type default)
			)
			(layer "F.SilkS")
		)
		(fp_line
			(start 1.7018 1.100074)
			(end -1.7018 1.100074)
			(stroke
				(width 0.1524)
				(type default)
			)
			(layer "F.SilkS")
		)
		(fp_line
			(start -1.7018 -1.100074)
			(end 1.7018 -1.100074)
			(stroke
				(width 0.1524)
				(type default)
			)
			(layer "F.SilkS")
		)
		(fp_line
			(start 1.7018 -1.100074)
			(end 1.7018 1.100074)
			(stroke
				(width 0.1524)
				(type default)
			)
			(layer "F.SilkS")
		)
		(fp_poly
			(pts
				(xy -2.277618 -0.710946) (xy -2.831338 -0.414274) (xy -2.831338 -1.039114)
			)
			(stroke
				(width 0)
				(type default)
			)
			(fill yes)
			(layer "F.SilkS")
		)
		(fp_line
			(start -0.670052 1.100074)
			(end -0.670052 0.8001)
			(stroke
				(width 0.1)
				(type default)
			)
			(layer "F.Fab")
		)
		(fp_line
			(start 0.670052 1.100074)
			(end -0.670052 1.100074)
			(stroke
				(width 0.1)
				(type default)
			)
			(layer "F.Fab")
		)
		(fp_line
			(start -1.100074 0.8001)
			(end -1.100074 -0.8001)
			(stroke
				(width 0.1)
				(type default)
			)
			(layer "F.Fab")
		)
		(fp_line
			(start -0.670052 0.8001)
			(end -1.100074 0.8001)
			(stroke
				(width 0.1)
				(type default)
			)
			(layer "F.Fab")
		)
		(fp_line
			(start -0.670052 0.8001)
			(end -0.670052 -0.8001)
			(stroke
				(width 0.1)
				(type default)
			)
			(layer "F.Fab")
		)
		(fp_line
			(start 0.670052 0.8001)
			(end 0.670052 1.100074)
			(stroke
				(width 0.1)
				(type default)
			)
			(layer "F.Fab")
		)
		(fp_line
			(start 1.100074 0.8001)
			(end 0.670052 0.8001)
			(stroke
				(width 0.1)
				(type default)
			)
			(layer "F.Fab")
		)
		(fp_line
			(start -1.100074 -0.8001)
			(end -0.670052 -0.8001)
			(stroke
				(width 0.1)
				(type default)
			)
			(layer "F.Fab")
		)
		(fp_line
			(start -0.670052 -0.8001)
			(end -0.670052 -1.100074)
			(stroke
				(width 0.1)
				(type default)
			)
			(layer "F.Fab")
		)
		(fp_line
			(start 0.670052 -0.8001)
			(end 0.670052 0.8001)
			(stroke
				(width 0.1)
				(type default)
			)
			(layer "F.Fab")
		)
		(fp_line
			(start 0.670052 -0.8001)
			(end 1.100074 -0.8001)
			(stroke
				(width 0.1)
				(type default)
			)
			(layer "F.Fab")
		)
		(fp_line
			(start 1.100074 -0.8001)
			(end 1.100074 0.8001)
			(stroke
				(width 0.1)
				(type default)
			)
			(layer "F.Fab")
		)
		(fp_line
			(start -0.670052 -1.100074)
			(end 0.670052 -1.100074)
			(stroke
				(width 0.1)
				(type default)
			)
			(layer "F.Fab")
		)
		(fp_line
			(start 0.670052 -1.100074)
			(end 0.670052 -0.8001)
			(stroke
				(width 0.1)
				(type default)
			)
			(layer "F.Fab")
		)
		(fp_poly
			(pts
				(xy -2.33172 -0.338328) (xy -2.33172 -0.963168) (xy -1.778 -0.635)
			)
			(stroke
				(width 0)
				(type default)
			)
			(fill yes)
			(layer "F.Fab")
		)
		(pad "1" smd rect
			(at -0.937514 -0.649986)
			(size 0.3048 1.2446)
			(layers "F.Cu" "F.Mask" "F.Paste")
			(net "GND")
		)
		(pad "2" smd rect
			(at -0.937514 0)
			(size 0.3048 1.2446)
			(layers "F.Cu" "F.Mask" "F.Paste")
			(net "PWRGD_P12V_MEM_CPU1_EN")
		)
		(pad "3" smd rect
			(at -0.937514 0.649986)
			(size 0.3048 1.2446)
			(layers "F.Cu" "F.Mask" "F.Paste")
			(net "PWRGD_P12V_MEM_CPU1")
		)
		(pad "4" smd rect
			(at 0.937514 0.649986)
			(size 0.3048 1.2446)
			(layers "F.Cu" "F.Mask" "F.Paste")
			(net "GND")
		)
		(pad "5" smd rect
			(at 0.937514 0)
			(size 0.3048 1.2446)
			(layers "F.Cu" "F.Mask" "F.Paste")
			(net "PWRGD_P12V_MEM_CPU1_EN_N")
		)
		(pad "6" smd rect
			(at 0.937514 -0.649986)
			(size 0.3048 1.2446)
			(layers "F.Cu" "F.Mask" "F.Paste")
			(net "PWRGD_P12V_MEM_CPU1_EN_N")
		)
	)
)
